FILE_TYPE = MULTI_PHYS_TABLE;

PART 'PCA9517AD'

{========================================================================================}
:VALUE       | PART_TYPE | MATERIAL | PART_NUMBER    = STANDARD | LIFECYCLE      | PART_NUMBER   | JEDEC_TYPE | DESCRIPTION                         | MANUFTR | MANUF_PN    | RD_CMPLS_LVL | CMPLS_LVL | FROM_PJ       | CLASS | DIP_SMD | DATA           | EE_CHECK_LIST | FP_ECN | PSL | CREATOR | STATUS | MSD | ESD_CDM | ESD_HBM | ESD_MM | PIN_LENGTH_SHORT_PIN | PIN_LENGTH_LONG_PIN | CREATEDAY  ;
{========================================================================================}
 'PCA9517AD' | 'SMLF'    | 'IC'     | 'AL009517000'(!) = ''       | ''               | 'AL009517000' |'SOIC8'| 'IC OTHER (8P) I2C PCA9517AD (SO8)' | 'NXP'   | 'PCA9517AD' | 'EP(V1)'     | 'EP(V1)'  | 'JB5_CHINWEI' | 'IC'  | ''      | 'PCA9517A.pdf' | ''            | ''     | ''  | ''      | ''     | ''  | ''      | ''      | ''     | '0 MILS'             | '0 MILS'            | '20200116'
 'PCA9517AD' | 'SMLF'    | 'EMPTY'  | 'AL009517000'(!) = ''       | ''               | 'AL009517000' |'SOIC8'| 'IC OTHER (8P) I2C PCA9517AD (SO8)' | 'NXP'   | 'PCA9517AD' | 'EP(V1)'     | 'EP(V1)'  | 'JB5_CHINWEI' | 'IC'  | ''      | 'PCA9517A.pdf' | ''            | ''     | ''  | ''      | ''     | ''  | ''      | ''      | ''     | '0 MILS'             | '0 MILS'            | '20200116'

END_PART

END.

